(kicad_pcb
	(version 20240108)
	(generator "pcbnew")
	(generator_version "8.0")
	(general
		(thickness 1.62)
		(legacy_teardrops no)
	)
	(paper "A4")
	(title_block
		(title "Jetson Orin Baseboard")
		(date "2025-03-12")
		(rev "1.3.4")
		(company "Antmicro Ltd")
		(comment 1 "www.antmicro.com")
		(comment 9 "footprints 94-98 of 677")
	)
	(layers
		(0 "F.Cu" signal)
		(1 "In1.Cu" signal)
		(2 "In2.Cu" signal)
		(3 "In3.Cu" signal)
		(4 "In4.Cu" jumper)
		(5 "In5.Cu" signal)
		(6 "In6.Cu" signal)
		(31 "B.Cu" signal)
		(32 "B.Adhes" user "B.Adhesive")
		(33 "F.Adhes" user "F.Adhesive")
		(34 "B.Paste" user)
		(35 "F.Paste" user)
		(36 "B.SilkS" user "B.Silkscreen")
		(37 "F.SilkS" user "F.Silkscreen")
		(38 "B.Mask" user)
		(39 "F.Mask" user)
		(40 "Dwgs.User" user "User.Drawings")
		(41 "Cmts.User" user "User.Comments")
		(42 "Eco1.User" user "User.Eco1")
		(43 "Eco2.User" user "User.Eco2")
		(44 "Edge.Cuts" user)
		(45 "Margin" user)
		(46 "B.CrtYd" user "B.Courtyard")
		(47 "F.CrtYd" user "F.Courtyard")
		(48 "B.Fab" user)
		(49 "F.Fab" user)
	)
	(footprint "antmicro-footprints:C_0402_1005Metric"
		(layer "F.Cu")
		(at 80.23 91.04 -90)
		(descr "Capacitor SMD 0402")
		(tags "capacitor SMD 0402")
		(property "Reference" "C155"
			(at -1.11 -1.52 90)
			(layer "F.SilkS")
			(effects
				(font
					(size 0.7 0.7)
					(thickness 0.15)
				)
				(justify right bottom)
			)
		)
		(property "Value" "C_4u7_25V_0402"
			(at -1.022927 2.155213 90)
			(layer "F.Fab")
			(effects
				(font
					(size 0.7 0.7)
					(thickness 0.15)
				)
				(justify right bottom)
			)
		)
		(property "Footprint" "antmicro-footprints:C_0402_1005Metric"
			(at 0 0 -90)
			(layer "F.Fab")
			(hide yes)
			(effects
				(font
					(size 1.27 1.27)
					(thickness 0.15)
				)
			)
		)
		(property "Datasheet" "https://www.murata.com/products/productdetail?partno=GRM155C61E475ME15%23"
			(at 0 0 -90)
			(layer "F.Fab")
			(hide yes)
			(effects
				(font
					(size 1.27 1.27)
					(thickness 0.15)
				)
			)
		)
		(property "Author" "Antmicro"
			(at -10.81 171.27 0)
			(layer "F.Fab")
			(hide yes)
			(effects
				(font
					(size 1 1)
					(thickness 0.15)
				)
			)
		)
		(property "Dielectric" "X5S"
			(at -10.81 171.27 0)
			(layer "F.Fab")
			(hide yes)
			(effects
				(font
					(size 1 1)
					(thickness 0.15)
				)
			)
		)
		(property "License" "Apache-2.0"
			(at -10.81 171.27 0)
			(layer "F.Fab")
			(hide yes)
			(effects
				(font
					(size 1 1)
					(thickness 0.15)
				)
			)
		)
		(property "MPN" "GRM155C61E475ME15J"
			(at -10.81 171.27 0)
			(layer "F.Fab")
			(hide yes)
			(effects
				(font
					(size 1 1)
					(thickness 0.15)
				)
			)
		)
		(property "Manufacturer" "Murata"
			(at -10.81 171.27 0)
			(layer "F.Fab")
			(hide yes)
			(effects
				(font
					(size 1 1)
					(thickness 0.15)
				)
			)
		)
		(property "Val" "4u7"
			(at -10.81 171.27 0)
			(layer "F.Fab")
			(hide yes)
			(effects
				(font
					(size 1 1)
					(thickness 0.15)
				)
			)
		)
		(property "Voltage" "25V"
			(at -10.81 171.27 0)
			(layer "F.Fab")
			(hide yes)
			(effects
				(font
					(size 1 1)
					(thickness 0.15)
				)
			)
		)
		(sheetname "Supply")
		(sheetfile "supply.kicad_sch")
		(attr smd)
		(fp_rect
			(start -0.925 -0.47)
			(end 0.925 0.47)
			(stroke
				(width 0.05)
				(type default)
			)
			(fill none)
			(layer "F.CrtYd")
		)
		(fp_line
			(start -0.494 0.248)
			(end -0.494 -0.25)
			(stroke
				(width 0.15)
				(type solid)
			)
			(layer "F.Fab")
		)
		(fp_line
			(start 0.504 0.248)
			(end -0.494 0.248)
			(stroke
				(width 0.15)
				(type solid)
			)
			(layer "F.Fab")
		)
		(fp_line
			(start -0.494 -0.25)
			(end 0.504 -0.25)
			(stroke
				(width 0.15)
				(type solid)
			)
			(layer "F.Fab")
		)
		(fp_line
			(start 0.504 -0.25)
			(end 0.504 0.248)
			(stroke
				(width 0.15)
				(type solid)
			)
			(layer "F.Fab")
		)
		(fp_text user "License: Apache-2.0"
			(at -0.939 5.799 90)
			(layer "F.Fab")
			(hide yes)
			(effects
				(font
					(size 0.7 0.7)
					(thickness 0.15)
				)
				(justify right bottom)
			)
		)
		(fp_text user "Author: Antmicro"
			(at -0.939 3.399 90)
			(layer "F.Fab")
			(hide yes)
			(effects
				(font
					(size 0.7 0.7)
					(thickness 0.15)
				)
				(justify right bottom)
			)
		)
		(fp_text user "${REFERENCE}"
			(at -0.939 4.599 90)
			(layer "F.Fab")
			(hide yes)
			(effects
				(font
					(size 0.7 0.7)
					(thickness 0.15)
				)
				(justify right bottom)
			)
		)
		(pad "1" smd roundrect
			(at -0.48 0 270)
			(size 0.59 0.64)
			(layers "F.Cu" "F.Paste" "F.Mask")
			(roundrect_rratio 0.25)
			(net 1 "GND")
			(pintype "passive")
		)
		(pad "2" smd roundrect
			(at 0.48 0 270)
			(size 0.59 0.64)
			(layers "F.Cu" "F.Paste" "F.Mask")
			(roundrect_rratio 0.25)
			(net 642 "/Supply/3V3_VDRV")
			(pintype "passive")
		)
	)
	(footprint "antmicro-footprints:C_0402_1005Metric"
		(layer "F.Cu")
		(at 68.67 99.42 -90)
		(descr "Capacitor SMD 0402")
		(tags "capacitor SMD 0402")
		(property "Reference" "C157"
			(at 0.73 -0.48 90)
			(layer "F.SilkS")
			(effects
				(font
					(size 0.7 0.7)
					(thickness 0.15)
				)
				(justify right bottom)
			)
		)
		(property "Value" "C_100n_0402"
			(at -1.022927 2.155213 90)
			(layer "F.Fab")
			(effects
				(font
					(size 0.7 0.7)
					(thickness 0.15)
				)
				(justify right bottom)
			)
		)
		(property "Footprint" "antmicro-footprints:C_0402_1005Metric"
			(at 0 0 -90)
			(layer "F.Fab")
			(hide yes)
			(effects
				(font
					(size 1.27 1.27)
					(thickness 0.15)
				)
			)
		)
		(property "Datasheet" "https://www.murata.com/products/productdetail?partno=GRM155R61H104KE14%23"
			(at 0 0 -90)
			(layer "F.Fab")
			(hide yes)
			(effects
				(font
					(size 1.27 1.27)
					(thickness 0.15)
				)
			)
		)
		(property "Author" "Antmicro"
			(at -30.75 168.09 0)
			(layer "F.Fab")
			(hide yes)
			(effects
				(font
					(size 1 1)
					(thickness 0.15)
				)
			)
		)
		(property "Dielectric" "X5R"
			(at -30.75 168.09 0)
			(layer "F.Fab")
			(hide yes)
			(effects
				(font
					(size 1 1)
					(thickness 0.15)
				)
			)
		)
		(property "License" "Apache-2.0"
			(at -30.75 168.09 0)
			(layer "F.Fab")
			(hide yes)
			(effects
				(font
					(size 1 1)
					(thickness 0.15)
				)
			)
		)
		(property "MPN" "GRM155R61H104KE14D"
			(at -30.75 168.09 0)
			(layer "F.Fab")
			(hide yes)
			(effects
				(font
					(size 1 1)
					(thickness 0.15)
				)
			)
		)
		(property "Manufacturer" "Murata"
			(at -30.75 168.09 0)
			(layer "F.Fab")
			(hide yes)
			(effects
				(font
					(size 1 1)
					(thickness 0.15)
				)
			)
		)
		(property "Val" "100n"
			(at -30.75 168.09 0)
			(layer "F.Fab")
			(hide yes)
			(effects
				(font
					(size 1 1)
					(thickness 0.15)
				)
			)
		)
		(property "Voltage" "50V"
			(at -30.75 168.09 0)
			(layer "F.Fab")
			(hide yes)
			(effects
				(font
					(size 1 1)
					(thickness 0.15)
				)
			)
		)
		(sheetname "Supply")
		(sheetfile "supply.kicad_sch")
		(attr smd)
		(fp_rect
			(start -0.925 -0.47)
			(end 0.925 0.47)
			(stroke
				(width 0.05)
				(type default)
			)
			(fill none)
			(layer "F.CrtYd")
		)
		(fp_line
			(start -0.494 0.248)
			(end -0.494 -0.25)
			(stroke
				(width 0.15)
				(type solid)
			)
			(layer "F.Fab")
		)
		(fp_line
			(start 0.504 0.248)
			(end -0.494 0.248)
			(stroke
				(width 0.15)
				(type solid)
			)
			(layer "F.Fab")
		)
		(fp_line
			(start -0.494 -0.25)
			(end 0.504 -0.25)
			(stroke
				(width 0.15)
				(type solid)
			)
			(layer "F.Fab")
		)
		(fp_line
			(start 0.504 -0.25)
			(end 0.504 0.248)
			(stroke
				(width 0.15)
				(type solid)
			)
			(layer "F.Fab")
		)
		(fp_text user "Author: Antmicro"
			(at -0.939 3.399 90)
			(layer "F.Fab")
			(hide yes)
			(effects
				(font
					(size 0.7 0.7)
					(thickness 0.15)
				)
				(justify right bottom)
			)
		)
		(fp_text user "${REFERENCE}"
			(at -0.939 4.599 90)
			(layer "F.Fab")
			(hide yes)
			(effects
				(font
					(size 0.7 0.7)
					(thickness 0.15)
				)
				(justify right bottom)
			)
		)
		(fp_text user "License: Apache-2.0"
			(at -0.939 5.799 90)
			(layer "F.Fab")
			(hide yes)
			(effects
				(font
					(size 0.7 0.7)
					(thickness 0.15)
				)
				(justify right bottom)
			)
		)
		(pad "1" smd roundrect
			(at -0.48 0 270)
			(size 0.59 0.64)
			(layers "F.Cu" "F.Paste" "F.Mask")
			(roundrect_rratio 0.25)
			(net 712 "/Supply/5V_EN")
			(pintype "passive")
		)
		(pad "2" smd roundrect
			(at 0.48 0 270)
			(size 0.59 0.64)
			(layers "F.Cu" "F.Paste" "F.Mask")
			(roundrect_rratio 0.25)
			(net 1 "GND")
			(pintype "passive")
		)
	)
	(footprint "antmicro-footprints:C_0603_1608Metric"
		(layer "F.Cu")
		(at 113.95 86.65 180)
		(descr "Capacitor SMD 0603")
		(tags "capacitor 0603")
		(property "Reference" "C11"
			(at -1.075 0.6 0)
			(layer "F.SilkS")
			(effects
				(font
					(size 0.7 0.7)
					(thickness 0.15)
				)
				(justify right bottom)
			)
		)
		(property "Value" "C_10u_0603"
			(at 0 1.6 0)
			(layer "F.Fab")
			(effects
				(font
					(size 0.7 0.7)
					(thickness 0.15)
				)
				(justify right bottom)
			)
		)
		(property "Footprint" "antmicro-footprints:C_0603_1608Metric"
			(at 0 0 180)
			(layer "F.Fab")
			(hide yes)
			(effects
				(font
					(size 1.27 1.27)
					(thickness 0.15)
				)
			)
		)
		(property "Datasheet" "https://www.murata.com/products/productdetail?partno=GRM188R61A106KE69%23"
			(at 0 0 180)
			(layer "F.Fab")
			(hide yes)
			(effects
				(font
					(size 1.27 1.27)
					(thickness 0.15)
				)
			)
		)
		(property "Author" "Antmicro"
			(at 227.9 173.3 0)
			(layer "F.Fab")
			(hide yes)
			(effects
				(font
					(size 1 1)
					(thickness 0.15)
				)
			)
		)
		(property "Dielectric" "template_dielectric"
			(at 227.9 173.3 0)
			(layer "F.Fab")
			(hide yes)
			(effects
				(font
					(size 1 1)
					(thickness 0.15)
				)
			)
		)
		(property "License" "Apache-2.0"
			(at 227.9 173.3 0)
			(layer "F.Fab")
			(hide yes)
			(effects
				(font
					(size 1 1)
					(thickness 0.15)
				)
			)
		)
		(property "MPN" "GRM188R61A106KE69D"
			(at 227.9 173.3 0)
			(layer "F.Fab")
			(hide yes)
			(effects
				(font
					(size 1 1)
					(thickness 0.15)
				)
			)
		)
		(property "Manufacturer" "Murata"
			(at 227.9 173.3 0)
			(layer "F.Fab")
			(hide yes)
			(effects
				(font
					(size 1 1)
					(thickness 0.15)
				)
			)
		)
		(property "Val" "10u"
			(at 227.9 173.3 0)
			(layer "F.Fab")
			(hide yes)
			(effects
				(font
					(size 1 1)
					(thickness 0.15)
				)
			)
		)
		(property "Voltage" ""
			(at 227.9 173.3 0)
			(layer "F.Fab")
			(hide yes)
			(effects
				(font
					(size 1 1)
					(thickness 0.15)
				)
			)
		)
		(sheetname "M.2")
		(sheetfile "m-2.kicad_sch")
		(attr smd)
		(fp_line
			(start -0.15 0.4)
			(end 0.15 0.4)
			(stroke
				(width 0.15)
				(type solid)
			)
			(layer "F.SilkS")
		)
		(fp_line
			(start -0.15 -0.4)
			(end 0.15 -0.4)
			(stroke
				(width 0.15)
				(type solid)
			)
			(layer "F.SilkS")
		)
		(fp_rect
			(start -1.25 -0.65)
			(end 1.25 0.65)
			(stroke
				(width 0.05)
				(type solid)
			)
			(fill none)
			(layer "F.CrtYd")
		)
		(fp_rect
			(start -0.8 -0.4)
			(end 0.8 0.4)
			(stroke
				(width 0.15)
				(type solid)
			)
			(fill none)
			(layer "F.Fab")
		)
		(fp_text user "Author: Antmicro"
			(at -1.682 4.894 0)
			(layer "F.Fab")
			(hide yes)
			(effects
				(font
					(size 0.7 0.7)
					(thickness 0.15)
				)
				(justify right bottom)
			)
		)
		(fp_text user "License: Apache-2.0"
			(at -1.682 5.895 0)
			(layer "F.Fab")
			(hide yes)
			(effects
				(font
					(size 0.7 0.7)
					(thickness 0.15)
				)
				(justify right bottom)
			)
		)
		(fp_text user "${REFERENCE}"
			(at -1.682 3.895 0)
			(layer "F.Fab")
			(hide yes)
			(effects
				(font
					(size 0.7 0.7)
					(thickness 0.15)
				)
				(justify right bottom)
			)
		)
		(pad "1" smd roundrect
			(at -0.7 0 180)
			(size 0.8 1)
			(layers "F.Cu" "F.Paste" "F.Mask")
			(roundrect_rratio 0.2)
			(net 87 "+3V3")
			(pintype "passive")
		)
		(pad "2" smd roundrect
			(at 0.7 0 180)
			(size 0.8 1)
			(layers "F.Cu" "F.Paste" "F.Mask")
			(roundrect_rratio 0.2)
			(net 1 "GND")
			(pintype "passive")
		)
	)
	(footprint "antmicro-footprints:C_0402_1005Metric"
		(layer "F.Cu")
		(at 106.3 102.65 90)
		(descr "Capacitor SMD 0402")
		(tags "capacitor SMD 0402")
		(property "Reference" "C67"
			(at 0.75 0.45 90)
			(layer "F.SilkS")
			(effects
				(font
					(size 0.7 0.7)
					(thickness 0.15)
				)
				(justify left bottom)
			)
		)
		(property "Value" "C_100n_0402"
			(at 0 1.4 90)
			(layer "F.Fab")
			(effects
				(font
					(size 0.7 0.7)
					(thickness 0.15)
				)
				(justify left bottom)
			)
		)
		(property "Footprint" "antmicro-footprints:C_0402_1005Metric"
			(at 0 0 90)
			(layer "F.Fab")
			(hide yes)
			(effects
				(font
					(size 1.27 1.27)
					(thickness 0.15)
				)
			)
		)
		(property "Datasheet" "https://www.murata.com/products/productdetail?partno=GRM155R61H104KE14%23"
			(at 0 0 90)
			(layer "F.Fab")
			(hide yes)
			(effects
				(font
					(size 1.27 1.27)
					(thickness 0.15)
				)
			)
		)
		(property "Author" "Antmicro"
			(at 208.95 -3.65 0)
			(layer "F.Fab")
			(hide yes)
			(effects
				(font
					(size 1 1)
					(thickness 0.15)
				)
			)
		)
		(property "Dielectric" "X5R"
			(at 208.95 -3.65 0)
			(layer "F.Fab")
			(hide yes)
			(effects
				(font
					(size 1 1)
					(thickness 0.15)
				)
			)
		)
		(property "License" "Apache-2.0"
			(at 208.95 -3.65 0)
			(layer "F.Fab")
			(hide yes)
			(effects
				(font
					(size 1 1)
					(thickness 0.15)
				)
			)
		)
		(property "MPN" "GRM155R61H104KE14D"
			(at 208.95 -3.65 0)
			(layer "F.Fab")
			(hide yes)
			(effects
				(font
					(size 1 1)
					(thickness 0.15)
				)
			)
		)
		(property "Manufacturer" "Murata"
			(at 208.95 -3.65 0)
			(layer "F.Fab")
			(hide yes)
			(effects
				(font
					(size 1 1)
					(thickness 0.15)
				)
			)
		)
		(property "Val" "100n"
			(at 208.95 -3.65 0)
			(layer "F.Fab")
			(hide yes)
			(effects
				(font
					(size 1 1)
					(thickness 0.15)
				)
			)
		)
		(property "Voltage" "50V"
			(at 208.95 -3.65 0)
			(layer "F.Fab")
			(hide yes)
			(effects
				(font
					(size 1 1)
					(thickness 0.15)
				)
			)
		)
		(sheetname "USB3")
		(sheetfile "usb3.kicad_sch")
		(attr smd)
		(fp_rect
			(start -0.925 -0.47)
			(end 0.925 0.47)
			(stroke
				(width 0.05)
				(type default)
			)
			(fill none)
			(layer "F.CrtYd")
		)
		(fp_line
			(start 0.504 -0.25)
			(end 0.504 0.248)
			(stroke
				(width 0.15)
				(type solid)
			)
			(layer "F.Fab")
		)
		(fp_line
			(start -0.494 -0.25)
			(end 0.504 -0.25)
			(stroke
				(width 0.15)
				(type solid)
			)
			(layer "F.Fab")
		)
		(fp_line
			(start 0.504 0.248)
			(end -0.494 0.248)
			(stroke
				(width 0.15)
				(type solid)
			)
			(layer "F.Fab")
		)
		(fp_line
			(start -0.494 0.248)
			(end -0.494 -0.25)
			(stroke
				(width 0.15)
				(type solid)
			)
			(layer "F.Fab")
		)
		(fp_text user "License: Apache-2.0"
			(at -0.932 5.17 90)
			(layer "F.Fab")
			(hide yes)
			(effects
				(font
					(size 0.7 0.7)
					(thickness 0.15)
				)
				(justify left bottom)
			)
		)
		(fp_text user "${REFERENCE}"
			(at -0.932 3.168 90)
			(layer "F.Fab")
			(hide yes)
			(effects
				(font
					(size 0.7 0.7)
					(thickness 0.15)
				)
				(justify left bottom)
			)
		)
		(fp_text user "Author: Antmicro"
			(at -0.932 4.17 90)
			(layer "F.Fab")
			(hide yes)
			(effects
				(font
					(size 0.7 0.7)
					(thickness 0.15)
				)
				(justify left bottom)
			)
		)
		(pad "1" smd roundrect
			(at -0.48 0 90)
			(size 0.59 0.64)
			(layers "F.Cu" "F.Paste" "F.Mask")
			(roundrect_rratio 0.25)
			(net 99 "+5V")
			(pintype "passive")
		)
		(pad "2" smd roundrect
			(at 0.48 0 90)
			(size 0.59 0.64)
			(layers "F.Cu" "F.Paste" "F.Mask")
			(roundrect_rratio 0.25)
			(net 1 "GND")
			(pintype "passive")
		)
	)
	(footprint "antmicro-footprints:C_0402_1005Metric"
		(layer "F.Cu")
		(at 136.35 83.95 180)
		(descr "Capacitor SMD 0402")
		(tags "capacitor SMD 0402")
		(property "Reference" "C110"
			(at 3.6 -0.4 180)
			(layer "F.SilkS")
			(effects
				(font
					(size 0.7 0.7)
					(thickness 0.15)
				)
				(justify left bottom)
			)
		)
		(property "Value" "C_220n_0402"
			(at 0 1.4 180)
			(layer "F.Fab")
			(effects
				(font
					(size 0.7 0.7)
					(thickness 0.15)
				)
				(justify left bottom)
			)
		)
		(property "Footprint" "antmicro-footprints:C_0402_1005Metric"
			(at 0 0 180)
			(layer "F.Fab")
			(hide yes)
			(effects
				(font
					(size 1.27 1.27)
					(thickness 0.15)
				)
			)
		)
		(property "Datasheet" "https://www.yageo.com/en/Chart/Download/pdf/CC0402KRX5R6BB224"
			(at 0 0 180)
			(layer "F.Fab")
			(hide yes)
			(effects
				(font
					(size 1.27 1.27)
					(thickness 0.15)
				)
			)
		)
		(property "Author" "Antmicro"
			(at 272.7 167.9 0)
			(layer "F.Fab")
			(hide yes)
			(effects
				(font
					(size 1 1)
					(thickness 0.15)
				)
			)
		)
		(property "Dielectric" ""
			(at 272.7 167.9 0)
			(layer "F.Fab")
			(hide yes)
			(effects
				(font
					(size 1 1)
					(thickness 0.15)
				)
			)
		)
		(property "License" "Apache-2.0"
			(at 272.7 167.9 0)
			(layer "F.Fab")
			(hide yes)
			(effects
				(font
					(size 1 1)
					(thickness 0.15)
				)
			)
		)
		(property "MPN" "CC0402KRX5R6BB224"
			(at 272.7 167.9 0)
			(layer "F.Fab")
			(hide yes)
			(effects
				(font
					(size 1 1)
					(thickness 0.15)
				)
			)
		)
		(property "Manufacturer" "YAGEO"
			(at 272.7 167.9 0)
			(layer "F.Fab")
			(hide yes)
			(effects
				(font
					(size 1 1)
					(thickness 0.15)
				)
			)
		)
		(property "Val" "220n"
			(at 272.7 167.9 0)
			(layer "F.Fab")
			(hide yes)
			(effects
				(font
					(size 1 1)
					(thickness 0.15)
				)
			)
		)
		(property "Voltage" ""
			(at 272.7 167.9 0)
			(layer "F.Fab")
			(hide yes)
			(effects
				(font
					(size 1 1)
					(thickness 0.15)
				)
			)
		)
		(sheetname "Peripherals")
		(sheetfile "peripherals.kicad_sch")
		(attr smd)
		(fp_rect
			(start -0.925 -0.47)
			(end 0.925 0.47)
			(stroke
				(width 0.05)
				(type default)
			)
			(fill none)
			(layer "F.CrtYd")
		)
		(fp_line
			(start 0.504 0.248)
			(end -0.494 0.248)
			(stroke
				(width 0.15)
				(type solid)
			)
			(layer "F.Fab")
		)
		(fp_line
			(start 0.504 -0.25)
			(end 0.504 0.248)
			(stroke
				(width 0.15)
				(type solid)
			)
			(layer "F.Fab")
		)
		(fp_line
			(start -0.494 0.248)
			(end -0.494 -0.25)
			(stroke
				(width 0.15)
				(type solid)
			)
			(layer "F.Fab")
		)
		(fp_line
			(start -0.494 -0.25)
			(end 0.504 -0.25)
			(stroke
				(width 0.15)
				(type solid)
			)
			(layer "F.Fab")
		)
		(fp_text user "License: Apache-2.0"
			(at -0.932 5.17 180)
			(layer "F.Fab")
			(hide yes)
			(effects
				(font
					(size 0.7 0.7)
					(thickness 0.15)
				)
				(justify left bottom)
			)
		)
		(fp_text user "Author: Antmicro"
			(at -0.932 4.17 180)
			(layer "F.Fab")
			(hide yes)
			(effects
				(font
					(size 0.7 0.7)
					(thickness 0.15)
				)
				(justify left bottom)
			)
		)
		(fp_text user "${REFERENCE}"
			(at -0.932 3.168 180)
			(layer "F.Fab")
			(hide yes)
			(effects
				(font
					(size 0.7 0.7)
					(thickness 0.15)
				)
				(justify left bottom)
			)
		)
		(pad "1" smd roundrect
			(at -0.48 0 180)
			(size 0.59 0.64)
			(layers "F.Cu" "F.Paste" "F.Mask")
			(roundrect_rratio 0.25)
			(net 413 "/Peripherals/PCIE2_TX1_CONN_P")
			(pintype "passive")
		)
		(pad "2" smd roundrect
			(at 0.48 0 180)
			(size 0.59 0.64)
			(layers "F.Cu" "F.Paste" "F.Mask")
			(roundrect_rratio 0.25)
			(net 370 "PCIE2_TX1_P")
			(pintype "passive")
		)
	)
)
